# T6G (Grand Teton) — schematic parts with pin connectivity, parts 8238–8303 of 8303; source: Cadence DE-HDL packaged netlist (pstxprt.dat, pstxnet.dat, pstchip.dat)

U8002  APX80929SAG7  APX809-29SAG-7 IC  pkg SOT23_123XI  page 142
  1  GND  POWER  = GND
  2  RESET_L  OUT  = OCP_V3_2_P3V3_R1_PWRGD
  3  VCC  POWER  = P3V3_OCP_V3_2_R

U8003  APX80929SAG7  APX809-29SAG-7 IC  pkg SOT23_123XI  page 147
  1  GND  POWER  = GND
  2  RESET_L  OUT  = P3V3_E1S_PWRGD_0_R1
  3  VCC  POWER  = P3V3_E1S_0_R

U8004  74LVC2G07DW7  74LVC2G07DW-7 EMPTY  pkg SOT363_0-65_2X1-25XC  page 242
  1  \1a\  IN  = FM_AC_PWR_BTN_PLD_N
  2  GND  POWER  = GND
  3  \2a\  IN  = GND
  4  \2y\  OUT  = NC_U8004_2Y
  5  VCC  POWER  = P3V3_AUX
  6  \1y\  OUT  = FM_AC_PWR_BTN_PLD_ISO_R_N

U8005  LM4040AIM3X25NOPB  LM4040AIM3X-2.5/NOPB EMPTY  pkg SOT23_123_2-92X1-3  page 267
  1  \1+\  BI  = OC_P2V5_COMP
  2  \2-\  OUT  = GND
  3  \3\  BI  = NC

U8006  AP331AWG7  AP331AWG-7 EMPTY  pkg SOT25  page 267
  1  \in-\  IN  = OC_P2V5_COMP
  2  GND  POWER  = GND
  3  \in+\  IN  = HSC_OC_VOL
  4  OUTPUT  OUT  = HSC_D_OC_R2
  5  VCC  POWER  = P12V_AUX

U8007  LM4040AIM3X25NOPB  LM4040AIM3X-2.5/NOPB IC  pkg SOT23_123_2-92X1-3  page 268
  1  \1+\  BI  = UV_ADR_P2V5_COMP
  2  \2-\  OUT  = GND
  3  \3\  BI  = NC

U8008  AP331AWG7  AP331AWG-7 IC  pkg SOT25  page 268
  1  \in-\  IN  = UV_ADR_P2V5_COMP
  2  GND  POWER  = GND
  3  \in+\  IN  = P12V_AUX_UV_ADR_TRIGGER
  4  OUTPUT  OUT  = FM_UV_ADR_TRIGGER_N_R2
  5  VCC  POWER  = P12V_AUX

U8009  LM4040AIM3X25NOPB  LM4040AIM3X-2.5/NOPB IC  pkg SOT23_123_2-92X1-3  page 268
  1  \1+\  BI  = UV_P2V5_COMP
  2  \2-\  OUT  = GND
  3  \3\  BI  = NC

U8010  AP331AWG7  AP331AWG-7 IC  pkg SOT25  page 268
  1  \in-\  IN  = UV_P2V5_COMP
  2  GND  POWER  = GND
  3  \in+\  IN  = P12V_AUX_UV_TRIGGER
  4  OUTPUT  OUT  = IRQ_UV_DETECT_R2_N
  5  VCC  POWER  = P12V_AUX

U8082  74LVC1G126SE7  74LVC1G126SE-7 IC  pkg SOT353_0-65_2X1-25  page 133
  1  OE  IN  = PU_OCP_SFF_WAKE_OE
  2  A  IN  = IRQ_LVC3_OCP_SFF_WAKE_N
  3  GND  POWER  = GND
  4  Y  OUT  = OCP_SFF_WAKE_BUFF_N
  5  VCC  POWER  = P3V3_AUX

U9001  74LVC1G08W57  74LVC1G08W5-7 IC  pkg SOT25-5_0-95_3X1-6  page 136
  1  A  IN  = RST_PERST_OCP_SFF_R_N
  2  B  IN  = HP_LVC3_OCP_V3_1_PWRGD
  3  GND  POWER  = GND
  4  Y  OUT  = RST_PERST_OCP_SFF_BUF_R_N
  5  VCC  POWER  = P3V3_AUX

U9002  74LVC1G32GW  IC  pkg SMLF  page 136
  1  I0  IN  = HP_LVC3_OCP_V3_1_PWRGD_R1
  2  I1  IN  = FM_PLD_OCP_SFF_AUX_PWR_EN
  3  GND  POWER  = GND
  4  O  OUT  = OCP_SFF_AUX_PWR_EN_R3
  5  VCC  POWER  = P3V3_AUX

U9050  74LVC1G08W57  74LVC1G08W5-7 IC  pkg SOT25-5_0-95_3X1-6  page 136
  1  A  IN  = OCP_V3_1_P3V3_PWRGD
  2  B  IN  = HP_LVC3_OCP_V3_1_P12V_R2_PWRGD
  3  GND  POWER  = GND
  4  Y  OUT  = HP_LVC3_OCP_V3_1_PWRGD_R2
  5  VCC  POWER  = P3V3_AUX

U9051  74LVC1G08W57  74LVC1G08W5-7 IC  pkg SOT25-5_0-95_3X1-6  page 142
  1  A  IN  = OCP_V3_2_P3V3_PWRGD
  2  B  IN  = HP_LVC3_OCP_V3_2_P12V_PWRGD_R2
  3  GND  POWER  = GND
  4  Y  OUT  = HP_LVC3_OCP_V3_2_PWRGD_R2
  5  VCC  POWER  = P3V3_AUX

X1  TP_TDR_4P_FTS  TP_TDR_4P_DIP EMPTY  pkg TH  page 260
  1  S1  BI  = TDR_DIFF_80_TOP_DP
  2  P1  BI  = T1_GND
  3  P2  BI  = T1_GND
  4  S2  BI  = TDR_DIFF_80_TOP_DN

X2  TP_TDR_4P_FTS  TP_TDR_4P_DIP EMPTY  pkg TH  page 260
  1  S1  BI  = TDR_DIFF_80_IN1_DP
  2  P1  BI  = T1_GND
  3  P2  BI  = T1_GND
  4  S2  BI  = TDR_DIFF_80_IN1_DN

X3  TP_TDR_4P_FTS  TP_TDR_4P_DIP EMPTY  pkg TH  page 260
  1  S1  BI  = TDR_DIFF_80_IN2_DP
  2  P1  BI  = T1_GND
  3  P2  BI  = T1_GND
  4  S2  BI  = TDR_DIFF_80_IN2_DN

X4  TP_TDR_4P_FTS  TP_TDR_4P_DIP EMPTY  pkg TH  page 260
  1  S1  BI  = TDR_DIFF_80_IN3_DP
  2  P1  BI  = T1_GND
  3  P2  BI  = T1_GND
  4  S2  BI  = TDR_DIFF_80_IN3_DN

X5  TP_TDR_4P_FTS  TP_TDR_4P_DIP EMPTY  pkg TH  page 260
  1  S1  BI  = TDR_DIFF_80_IN4_DP
  2  P1  BI  = T1_GND
  3  P2  BI  = T1_GND
  4  S2  BI  = TDR_DIFF_80_IN4_DN

X6  TP_TDR_4P_FTS  TP_TDR_4P_DIP EMPTY  pkg TH  page 260
  1  S1  BI  = TDR_DIFF_80_BOT_DP
  2  P1  BI  = T1_GND
  3  P2  BI  = T1_GND
  4  S2  BI  = TDR_DIFF_80_BOT_DN

X7  TP_TDR_4P_FTS  TP_TDR_4P_DIP EMPTY  pkg TH  page 260
  1  S1  BI  = TDR_DIFF_80_TOP_DN
  2  P1  BI  = T1_GND
  3  P2  BI  = T1_GND
  4  S2  BI  = TDR_DIFF_80_TOP_DP

X8  TP_TDR_4P_FTS  TP_TDR_4P_DIP EMPTY  pkg TH  page 260
  1  S1  BI  = TDR_DIFF_80_IN1_DN
  2  P1  BI  = T1_GND
  3  P2  BI  = T1_GND
  4  S2  BI  = TDR_DIFF_80_IN1_DP

X9  TP_TDR_4P_FTS  TP_TDR_4P_DIP EMPTY  pkg TH  page 260
  1  S1  BI  = TDR_DIFF_80_IN2_DN
  2  P1  BI  = T1_GND
  3  P2  BI  = T1_GND
  4  S2  BI  = TDR_DIFF_80_IN2_DP

X10  TP_TDR_4P_FTS  TP_TDR_4P_DIP EMPTY  pkg TH  page 260
  1  S1  BI  = TDR_DIFF_80_IN3_DN
  2  P1  BI  = T1_GND
  3  P2  BI  = T1_GND
  4  S2  BI  = TDR_DIFF_80_IN3_DP

X11  TP_TDR_4P_FTS  TP_TDR_4P_DIP EMPTY  pkg TH  page 260
  1  S1  BI  = TDR_DIFF_80_IN4_DN
  2  P1  BI  = T1_GND
  3  P2  BI  = T1_GND
  4  S2  BI  = TDR_DIFF_80_IN4_DP

X12  TP_TDR_4P_FTS  TP_TDR_4P_DIP EMPTY  pkg TH  page 260
  1  S1  BI  = TDR_DIFF_80_BOT_DN
  2  P1  BI  = T1_GND
  3  P2  BI  = T1_GND
  4  S2  BI  = TDR_DIFF_80_BOT_DP

X25  TP_TDR_4P_FTS  TP_TDR_4P_DIP EMPTY  pkg TH  page 260
  1  S1  BI  = TDR_DIFF_80_IN5_DP
  2  P1  BI  = T1_GND
  3  P2  BI  = T1_GND
  4  S2  BI  = TDR_DIFF_80_IN5_DN

X26  TP_TDR_4P_FTS  TP_TDR_4P_DIP EMPTY  pkg TH  page 260
  1  S1  BI  = TDR_DIFF_80_IN6_DP
  2  P1  BI  = T1_GND
  3  P2  BI  = T1_GND
  4  S2  BI  = TDR_DIFF_80_IN6_DN

X27  TP_TDR_4P_FTS  TP_TDR_4P_DIP EMPTY  pkg TH  page 260
  1  S1  BI  = TDR_DIFF_80_IN5_DN
  2  P1  BI  = T1_GND
  3  P2  BI  = T1_GND
  4  S2  BI  = TDR_DIFF_80_IN5_DP

X28  TP_TDR_4P_FTS  TP_TDR_4P_DIP EMPTY  pkg TH  page 260
  1  S1  BI  = TDR_DIFF_80_IN6_DN
  2  P1  BI  = T1_GND
  3  P2  BI  = T1_GND
  4  S2  BI  = TDR_DIFF_80_IN6_DP

X8001  TP_TDR_4P_FTS  TP_TDR_4P_DIP EMPTY  pkg TH  page 260
  1  S1  BI  = TDR_DIFF_85_TOP_DP
  2  P1  BI  = T1_GND
  3  P2  BI  = T1_GND
  4  S2  BI  = TDR_DIFF_85_TOP_DN

X8002  TP_TDR_4P_FTS  TP_TDR_4P_DIP EMPTY  pkg TH  page 260
  1  S1  BI  = TDR_DIFF_85_IN1_DP
  2  P1  BI  = T1_GND
  3  P2  BI  = T1_GND
  4  S2  BI  = TDR_DIFF_85_IN1_DN

X8003  TP_TDR_4P_FTS  TP_TDR_4P_DIP EMPTY  pkg TH  page 260
  1  S1  BI  = TDR_DIFF_85_IN2_DP
  2  P1  BI  = T1_GND
  3  P2  BI  = T1_GND
  4  S2  BI  = TDR_DIFF_85_IN2_DN

X8004  TP_TDR_4P_FTS  TP_TDR_4P_DIP EMPTY  pkg TH  page 260
  1  S1  BI  = TDR_DIFF_85_IN3_DP
  2  P1  BI  = T1_GND
  3  P2  BI  = T1_GND
  4  S2  BI  = TDR_DIFF_85_IN3_DN

X8005  TP_TDR_4P_FTS  TP_TDR_4P_DIP EMPTY  pkg TH  page 260
  1  S1  BI  = TDR_DIFF_85_IN4_DP
  2  P1  BI  = T1_GND
  3  P2  BI  = T1_GND
  4  S2  BI  = TDR_DIFF_85_IN4_DN

X8006  TP_TDR_4P_FTS  TP_TDR_4P_DIP EMPTY  pkg TH  page 260
  1  S1  BI  = TDR_DIFF_85_BOT_DP
  2  P1  BI  = T1_GND
  3  P2  BI  = T1_GND
  4  S2  BI  = TDR_DIFF_85_BOT_DN

X8007  TP_TDR_4P_FTS  TP_TDR_4P_DIP EMPTY  pkg TH  page 260
  1  S1  BI  = TDR_DIFF_85_TOP_DN
  2  P1  BI  = T1_GND
  3  P2  BI  = T1_GND
  4  S2  BI  = TDR_DIFF_85_TOP_DP

X8008  TP_TDR_4P_FTS  TP_TDR_4P_DIP EMPTY  pkg TH  page 260
  1  S1  BI  = TDR_DIFF_85_IN1_DN
  2  P1  BI  = T1_GND
  3  P2  BI  = T1_GND
  4  S2  BI  = TDR_DIFF_85_IN1_DP

X8009  TP_TDR_4P_FTS  TP_TDR_4P_DIP EMPTY  pkg TH  page 260
  1  S1  BI  = TDR_DIFF_85_IN2_DN
  2  P1  BI  = T1_GND
  3  P2  BI  = T1_GND
  4  S2  BI  = TDR_DIFF_85_IN2_DP

X8010  TP_TDR_4P_FTS  TP_TDR_4P_DIP EMPTY  pkg TH  page 260
  1  S1  BI  = TDR_DIFF_85_IN3_DN
  2  P1  BI  = T1_GND
  3  P2  BI  = T1_GND
  4  S2  BI  = TDR_DIFF_85_IN3_DP

X8011  TP_TDR_4P_FTS  TP_TDR_4P_DIP EMPTY  pkg TH  page 260
  1  S1  BI  = TDR_DIFF_85_IN4_DN
  2  P1  BI  = T1_GND
  3  P2  BI  = T1_GND
  4  S2  BI  = TDR_DIFF_85_IN4_DP

X8012  TP_TDR_4P_FTS  TP_TDR_4P_DIP EMPTY  pkg TH  page 260
  1  S1  BI  = TDR_DIFF_85_BOT_DN
  2  P1  BI  = T1_GND
  3  P2  BI  = T1_GND
  4  S2  BI  = TDR_DIFF_85_BOT_DP

X8025  TP_TDR_4P_FTS  TP_TDR_4P_DIP EMPTY  pkg TH  page 260
  1  S1  BI  = TDR_DIFF_85_IN5_DP
  2  P1  BI  = T1_GND
  3  P2  BI  = T1_GND
  4  S2  BI  = TDR_DIFF_85_IN5_DN

X8026  TP_TDR_4P_FTS  TP_TDR_4P_DIP EMPTY  pkg TH  page 260
  1  S1  BI  = TDR_DIFF_85_IN6_DP
  2  P1  BI  = T1_GND
  3  P2  BI  = T1_GND
  4  S2  BI  = TDR_DIFF_85_IN6_DN

X8027  TP_TDR_4P_FTS  TP_TDR_4P_DIP EMPTY  pkg TH  page 260
  1  S1  BI  = TDR_DIFF_85_IN5_DN
  2  P1  BI  = T1_GND
  3  P2  BI  = T1_GND
  4  S2  BI  = TDR_DIFF_85_IN5_DP

X8028  TP_TDR_4P_FTS  TP_TDR_4P_DIP EMPTY  pkg TH  page 260
  1  S1  BI  = TDR_DIFF_85_IN6_DN
  2  P1  BI  = T1_GND
  3  P2  BI  = T1_GND
  4  S2  BI  = TDR_DIFF_85_IN6_DP

X9002  TP_TDR_4P_FTS  TP_TDR_4P_DIP EMPTY  pkg TH  page 261
  1  S1  BI  = TDR_DIFF_85_NECK_IN1_DP
  2  P1  BI  = T1_GND
  3  P2  BI  = T1_GND
  4  S2  BI  = TDR_DIFF_85_NECK_IN1_DN

X9003  TP_TDR_4P_FTS  TP_TDR_4P_DIP EMPTY  pkg TH  page 261
  1  S1  BI  = TDR_DIFF_85_NECK_IN2_DP
  2  P1  BI  = T1_GND
  3  P2  BI  = T1_GND
  4  S2  BI  = TDR_DIFF_85_NECK_IN2_DN

X9004  TP_TDR_4P_FTS  TP_TDR_4P_DIP EMPTY  pkg TH  page 261
  1  S1  BI  = TDR_DIFF_85_NECK_IN3_DP
  2  P1  BI  = T1_GND
  3  P2  BI  = T1_GND
  4  S2  BI  = TDR_DIFF_85_NECK_IN3_DN

X9005  TP_TDR_4P_FTS  TP_TDR_4P_DIP EMPTY  pkg TH  page 261
  1  S1  BI  = TDR_DIFF_85_NECK_IN4_DP
  2  P1  BI  = T1_GND
  3  P2  BI  = T1_GND
  4  S2  BI  = TDR_DIFF_85_NECK_IN4_DN

X9008  TP_TDR_4P_FTS  TP_TDR_4P_DIP EMPTY  pkg TH  page 261
  1  S1  BI  = TDR_DIFF_85_NECK_IN1_DN
  2  P1  BI  = T1_GND
  3  P2  BI  = T1_GND
  4  S2  BI  = TDR_DIFF_85_NECK_IN1_DP

X9009  TP_TDR_4P_FTS  TP_TDR_4P_DIP EMPTY  pkg TH  page 261
  1  S1  BI  = TDR_DIFF_85_NECK_IN2_DN
  2  P1  BI  = T1_GND
  3  P2  BI  = T1_GND
  4  S2  BI  = TDR_DIFF_85_NECK_IN2_DP

X9010  TP_TDR_4P_FTS  TP_TDR_4P_DIP EMPTY  pkg TH  page 261
  1  S1  BI  = TDR_DIFF_85_NECK_IN3_DN
  2  P1  BI  = T1_GND
  3  P2  BI  = T1_GND
  4  S2  BI  = TDR_DIFF_85_NECK_IN3_DP

X9011  TP_TDR_4P_FTS  TP_TDR_4P_DIP EMPTY  pkg TH  page 261
  1  S1  BI  = TDR_DIFF_85_NECK_IN4_DN
  2  P1  BI  = T1_GND
  3  P2  BI  = T1_GND
  4  S2  BI  = TDR_DIFF_85_NECK_IN4_DP

X9025  TP_TDR_4P_FTS  TP_TDR_4P_DIP EMPTY  pkg TH  page 261
  1  S1  BI  = TDR_DIFF_85_NECK_IN5_DP
  2  P1  BI  = T1_GND
  3  P2  BI  = T1_GND
  4  S2  BI  = TDR_DIFF_85_NECK_IN5_DN

X9026  TP_TDR_4P_FTS  TP_TDR_4P_DIP EMPTY  pkg TH  page 261
  1  S1  BI  = TDR_DIFF_85_NECK_IN6_DP
  2  P1  BI  = T1_GND
  3  P2  BI  = T1_GND
  4  S2  BI  = TDR_DIFF_85_NECK_IN6_DN

X9027  TP_TDR_4P_FTS  TP_TDR_4P_DIP EMPTY  pkg TH  page 261
  1  S1  BI  = TDR_DIFF_85_NECK_IN5_DN
  2  P1  BI  = T1_GND
  3  P2  BI  = T1_GND
  4  S2  BI  = TDR_DIFF_85_NECK_IN5_DP

X9028  TP_TDR_4P_FTS  TP_TDR_4P_DIP EMPTY  pkg TH  page 261
  1  S1  BI  = TDR_DIFF_85_NECK_IN6_DN
  2  P1  BI  = T1_GND
  3  P2  BI  = T1_GND
  4  S2  BI  = TDR_DIFF_85_NECK_IN6_DP

Y2  Q_XTAL_4P_13BI_24GND  48MHZ MISC  pkg X_4S_FL4000120_3-2X2-5  page 28
  1  X1  BI  = XTAL_CPU0_X48M_X1
  2  G1  POWER  = GND
  3  X2  BI  = XTAL_CPU0_X48M_X2_R
  4  G2  POWER  = GND

Y3  Q_CRYSTAL  32.768KHZ IC  pkg SMLF  page 28 : 1 = XTAL_CPU0_X32K_X1 ; 2 = XTAL_CPU0_X32K_X2

Y4  Q_XTAL_4P_13BI_24GND  48MHZ MISC  pkg X_4S_FL4000120_3-2X2-5  page 55
  1  X1  BI  = XTAL_CPU1_X48M_X1
  2  G1  POWER  = GND
  3  X2  BI  = XTAL_CPU1_X48M_X2_R
  4  G2  POWER  = GND

Y5  Q_CRYSTAL  32.768KHZ EMPTY  pkg SMLF  page 55 : 1 = XTAL_CPU1_R_X32K_X1 ; 2 = XTAL_CPU1_R_X32K_X2

Y9  Q_XTAL_4P_13BI_24GND  26MHZ MISC  pkg X_4S_8Z25000020_2-5X2  page 176
  1  X1  BI  = XTAL_USB_CPU0_HUB1_XIN
  2  G1  POWER  = GND
  3  X2  BI  = XTAL_USB_CPU0_HUB1_XOUT
  4  G2  POWER  = GND

Y6000  Q_XTAL_4P_13BI_24GND  24MHZ MISC  pkg X_7MXA  page 179
  1  X1  BI  = XTAL_USB_CPU0_HUB2_XIN
  2  G1  POWER  = GND
  3  X2  BI  = XTAL_USB_CPU0_HUB2_XOUT
  4  G2  POWER  = GND

Y8003  Q_XTAL_4P_13BI_24GND  25MHZ MISC  pkg OSC4_E3FB  page 233
  1  X1  BI  = CLK_GEN2_XTAL_IN_R
  2  G1  POWER  = GND
  3  X2  BI  = CLK_GEN2_XTAL_OUT
  4  G2  POWER  = GND

Y8004  Q_XTAL_4P_13BI_24GND  12MHZ MISC  pkg X_4S_8Z25000020_2-5X2  page 234
  1  X1  BI  = USB_HUB_XTAL_IN
  2  G1  POWER  = GND
  3  X2  BI  = USB_HUB_XTAL_OUT
  4  G2  POWER  = GND
